# S9S_MB_2U (Grand Teton) — schematic netlist excerpt (pin names and nets, part order shuffled) for the footprints in the layout excerpt that follows; sources: Cadence DE-HDL packaged netlist, KiCad conversion of 03242023_DA0F0TMBIJ0_F0T_Motherboard_J_brd_V01_OCP.brd

R4419  Q_RES  49.9 1% EMPTY  pkg 0402LF  page 152 : A = USB2_HOST_BMC_B_DP ; B = GND

Q139  BC847BPN  IC  pkg SOT363XB  page 121
  E1  = GND
  B1  = H_CPU1_THERMTRIP_R_N
  C2  = H_CPU1_THERMTRIP_N
  E2  = PVNN_TERM_CPU1
  B2  = H_CPU1_THERMTRIP_VT_R_N
  C1  = H_CPU1_THERMTRIP_VT_N

(kicad_pcb
	(version 20260206)
	(generator "pcbnew")
	(generator_version "10.0")
	(general
		(thickness 1.6)
		(legacy_teardrops no)
	)
	(paper "A4")
	(title_block
		(title "03242023_DA0F0TMBIJ0_F0T_Motherboard_J_brd_V01_OCP.brd")
		(comment 1 "Grand Teton / footprints 1284-1285 of 6105")
	)
	(layers
		(0 "F.Cu" signal "TOP")
		(4 "In1.Cu" signal "GND")
		(6 "In2.Cu" signal "IN1")
		(8 "In3.Cu" signal "GND1")
		(10 "In4.Cu" signal "IN2")
		(12 "In5.Cu" signal "GND2")
		(14 "In6.Cu" signal "IN3")
		(16 "In7.Cu" signal "GND3")
		(18 "In8.Cu" signal "VCC")
		(20 "In9.Cu" signal "VCC1")
		(22 "In10.Cu" signal "GND4")
		(24 "In11.Cu" signal "IN4")
		(26 "In12.Cu" signal "GND5")
		(28 "In13.Cu" signal "IN5")
		(30 "In14.Cu" signal "GND6")
		(32 "In15.Cu" signal "IN6")
		(34 "In16.Cu" signal "GND7")
		(2 "B.Cu" signal "BOTTOM")
		(9 "F.Adhes" user "F.Adhesive")
		(11 "B.Adhes" user "B.Adhesive")
		(13 "F.Paste" user "Package Geometry/Pastemask Top")
		(15 "B.Paste" user "Package Geometry/Pastemask Bottom")
		(5 "F.SilkS" user "Ref Des/Silkscreen Top")
		(7 "B.SilkS" user "Ref Des/Silkscreen Bottom")
		(1 "F.Mask" user "Board Geometry/Soldermask Top")
		(3 "B.Mask" user "Board Geometry/Soldermask Bottom")
		(17 "Dwgs.User" user "User.Drawings")
		(19 "Cmts.User" user "User.Comments")
		(21 "Eco1.User" user "User.Eco1")
		(23 "Eco2.User" user "User.Eco2")
		(25 "Edge.Cuts" user "Board Geometry/Outline")
		(27 "Margin" user)
		(31 "F.CrtYd" user "Package Geometry/Place Bound Top")
		(29 "B.CrtYd" user "Package Geometry/Place Bound Bottom")
		(35 "F.Fab" user "Ref Des/Assembly Top")
		(33 "B.Fab" user "Ref Des/Assembly Bottom")
	)
	(footprint ""
		(layer "F.Cu")
		(at 14.265402 -105.537762 90)
		(property "Reference" "R4419"
			(at 0 0 90)
			(layer "F.SilkS")
			(hide yes)
			(effects
				(font
					(size 1.27 1.27)
				)
			)
		)
		(property "Value" ""
			(at 0 0 90)
			(layer "F.Fab")
			(effects
				(font
					(size 1.27 1.27)
				)
			)
		)
		(duplicate_pad_numbers_are_jumpers no)
		(fp_line
			(start 0.7874 -0.4064)
			(end 0.7874 0.4064)
			(stroke
				(width 0.1524)
				(type default)
			)
			(layer "F.SilkS")
		)
		(fp_line
			(start -0.7874 -0.4064)
			(end 0.7874 -0.4064)
			(stroke
				(width 0.1524)
				(type default)
			)
			(layer "F.SilkS")
		)
		(fp_line
			(start 0.7874 0.4064)
			(end 0.004318 0.4064)
			(stroke
				(width 0.1524)
				(type default)
			)
			(layer "F.SilkS")
		)
		(fp_line
			(start -0.7874 0.4064)
			(end -0.7874 -0.4064)
			(stroke
				(width 0.1524)
				(type default)
			)
			(layer "F.SilkS")
		)
		(fp_line
			(start -0.12065 -0.305054)
			(end -0.12065 -0.2794)
			(stroke
				(width 0.1)
				(type default)
			)
			(layer "F.Fab")
		)
		(fp_line
			(start -0.67945 -0.305054)
			(end -0.12065 -0.305054)
			(stroke
				(width 0.1)
				(type default)
			)
			(layer "F.Fab")
		)
		(fp_line
			(start 0.67945 -0.3048)
			(end 0.67945 0.3048)
			(stroke
				(width 0.1)
				(type default)
			)
			(layer "F.Fab")
		)
		(fp_line
			(start 0.12065 -0.3048)
			(end 0.67945 -0.3048)
			(stroke
				(width 0.1)
				(type default)
			)
			(layer "F.Fab")
		)
		(fp_line
			(start 0.12065 -0.2794)
			(end 0.12065 -0.3048)
			(stroke
				(width 0.1)
				(type default)
			)
			(layer "F.Fab")
		)
		(fp_line
			(start -0.12065 -0.2794)
			(end 0.12065 -0.2794)
			(stroke
				(width 0.1)
				(type default)
			)
			(layer "F.Fab")
		)
		(fp_line
			(start 0.120396 0.2794)
			(end -0.12065 0.2794)
			(stroke
				(width 0.1)
				(type default)
			)
			(layer "F.Fab")
		)
		(fp_line
			(start -0.12065 0.2794)
			(end -0.12065 0.3048)
			(stroke
				(width 0.1)
				(type default)
			)
			(layer "F.Fab")
		)
		(fp_line
			(start 0.67945 0.3048)
			(end 0.120396 0.3048)
			(stroke
				(width 0.1)
				(type default)
			)
			(layer "F.Fab")
		)
		(fp_line
			(start 0.120396 0.3048)
			(end 0.120396 0.2794)
			(stroke
				(width 0.1)
				(type default)
			)
			(layer "F.Fab")
		)
		(fp_line
			(start -0.12065 0.3048)
			(end -0.67945 0.3048)
			(stroke
				(width 0.1)
				(type default)
			)
			(layer "F.Fab")
		)
		(fp_line
			(start -0.67945 0.3048)
			(end -0.67945 -0.305054)
			(stroke
				(width 0.1)
				(type default)
			)
			(layer "F.Fab")
		)
		(pad "1" smd circle
			(at -0.40005 0 90)
			(size 0 0)
			(layers "F.Cu" "F.Mask" "F.Paste")
			(net "USB2_HOST_BMC_B_DP")
		)
		(pad "2" smd circle
			(at 0.40005 0 90)
			(size 0 0)
			(layers "F.Cu" "F.Mask" "F.Paste")
			(net "GND")
		)
	)
	(footprint ""
		(layer "F.Cu")
		(at 126.01448 -96.258126 -90)
		(property "Reference" "Q139"
			(at -4.103624 0.79248 0)
			(unlocked yes)
			(layer "F.SilkS")
			(effects
				(font
					(size 0.635 0.4064)
					(thickness 0.1524)
				)
			)
		)
		(property "Value" ""
			(at 0 0 270)
			(layer "F.Fab")
			(effects
				(font
					(size 1.27 1.27)
				)
			)
		)
		(duplicate_pad_numbers_are_jumpers no)
		(fp_line
			(start -1.376172 1.199896)
			(end -1.376172 -1.199896)
			(stroke
				(width 0.1524)
				(type default)
			)
			(layer "F.SilkS")
		)
		(fp_line
			(start 1.376172 1.199896)
			(end -1.376172 1.199896)
			(stroke
				(width 0.1524)
				(type default)
			)
			(layer "F.SilkS")
		)
		(fp_line
			(start 0 -0.762)
			(end 0.508 -1.199896)
			(stroke
				(width 0.1524)
				(type default)
			)
			(layer "F.SilkS")
		)
		(fp_line
			(start -1.376172 -1.199896)
			(end -0.508 -1.199896)
			(stroke
				(width 0.1524)
				(type default)
			)
			(layer "F.SilkS")
		)
		(fp_line
			(start -0.508 -1.199896)
			(end 0 -0.762)
			(stroke
				(width 0.1524)
				(type default)
			)
			(layer "F.SilkS")
		)
		(fp_line
			(start 0.508 -1.199896)
			(end 1.376172 -1.199896)
			(stroke
				(width 0.1524)
				(type default)
			)
			(layer "F.SilkS")
		)
		(fp_line
			(start 1.376172 -1.199896)
			(end 1.376172 1.199896)
			(stroke
				(width 0.1524)
				(type default)
			)
			(layer "F.SilkS")
		)
		(fp_poly
			(pts
				(xy -1.5875 -0.7493) (xy -2.3495 -1.1303) (xy -2.3495 -0.3683)
			)
			(stroke
				(width 0)
				(type default)
			)
			(fill yes)
			(layer "F.SilkS")
		)
		(fp_line
			(start -0.674878 1.100074)
			(end -0.674878 -1.100074)
			(stroke
				(width 0.1)
				(type default)
			)
			(layer "F.Fab")
		)
		(fp_line
			(start 0.674878 1.100074)
			(end -0.674878 1.100074)
			(stroke
				(width 0.1)
				(type default)
			)
			(layer "F.Fab")
		)
		(fp_line
			(start -0.674878 -1.100074)
			(end 0.674878 -1.100074)
			(stroke
				(width 0.1)
				(type default)
			)
			(layer "F.Fab")
		)
		(fp_line
			(start 0.674878 -1.100074)
			(end 0.674878 1.100074)
			(stroke
				(width 0.1)
				(type default)
			)
			(layer "F.Fab")
		)
		(fp_poly
			(pts
				(xy -1.4605 -0.7493) (xy -2.2225 -1.1303) (xy -2.2225 -0.3683)
			)
			(stroke
				(width 0)
				(type default)
			)
			(fill yes)
			(layer "F.Fab")
		)
		(pad "1" smd rect
			(at -0.899922 -0.750062 180)
			(size 0.6096 0.6096)
			(layers "F.Cu" "F.Mask" "F.Paste")
			(net "GND")
		)
		(pad "2" smd rect
			(at -0.899922 0 180)
			(size 0.4064 0.6096)
			(layers "F.Cu" "F.Mask" "F.Paste")
			(net "H_CPU1_THERMTRIP_R_N")
		)
		(pad "3" smd rect
			(at -0.899922 0.750062 180)
			(size 0.6096 0.6096)
			(layers "F.Cu" "F.Mask" "F.Paste")
			(net "H_CPU1_THERMTRIP_N")
		)
		(pad "4" smd rect
			(at 0.899922 0.750062 180)
			(size 0.6096 0.6096)
			(layers "F.Cu" "F.Mask" "F.Paste")
			(net "PVNN_TERM_CPU1")
		)
		(pad "5" smd rect
			(at 0.899922 0 180)
			(size 0.4064 0.6096)
			(layers "F.Cu" "F.Mask" "F.Paste")
			(net "H_CPU1_THERMTRIP_VT_R_N")
		)
		(pad "6" smd rect
			(at 0.899922 -0.750062 180)
			(size 0.6096 0.6096)
			(layers "F.Cu" "F.Mask" "F.Paste")
			(net "H_CPU1_THERMTRIP_VT_N")
		)
	)
)
